(kicad_pcb
	(version 20260206)
	(generator "pcbnew")
	(generator_version "10.0")
	(general
		(thickness 1.6)
		(legacy_teardrops no)
	)
	(paper "A4")
	(title_block
		(title "04192023_DAF0TMB3IC0_F0TG_MB_C_brd_V02_OCP.brd")
		(comment 1 "Grand Teton / footprints 5502-5508 of 8354")
	)
	(layers
		(0 "F.Cu" signal "TOP")
		(4 "In1.Cu" signal "GND")
		(6 "In2.Cu" signal "IN1")
		(8 "In3.Cu" signal "GND1")
		(10 "In4.Cu" signal "IN2")
		(12 "In5.Cu" signal "GND2")
		(14 "In6.Cu" signal "IN3")
		(16 "In7.Cu" signal "GND3")
		(18 "In8.Cu" signal "VCC")
		(20 "In9.Cu" signal "VCC1")
		(22 "In10.Cu" signal "GND4")
		(24 "In11.Cu" signal "IN4")
		(26 "In12.Cu" signal "GND5")
		(28 "In13.Cu" signal "IN5")
		(30 "In14.Cu" signal "GND6")
		(32 "In15.Cu" signal "IN6")
		(34 "In16.Cu" signal "GND7")
		(2 "B.Cu" signal "BOTTOM")
		(9 "F.Adhes" user "F.Adhesive")
		(11 "B.Adhes" user "B.Adhesive")
		(13 "F.Paste" user "Package Geometry/Pastemask Top")
		(15 "B.Paste" user "Package Geometry/Pastemask Bottom")
		(5 "F.SilkS" user "Ref Des/Silkscreen Top")
		(7 "B.SilkS" user "Ref Des/Silkscreen Bottom")
		(1 "F.Mask" user "Board Geometry/Soldermask Top")
		(3 "B.Mask" user "Board Geometry/Soldermask Bottom")
		(17 "Dwgs.User" user "User.Drawings")
		(19 "Cmts.User" user "User.Comments")
		(21 "Eco1.User" user "User.Eco1")
		(23 "Eco2.User" user "User.Eco2")
		(25 "Edge.Cuts" user "Board Geometry/Outline")
		(27 "Margin" user)
		(31 "F.CrtYd" user "Package Geometry/Place Bound Top")
		(29 "B.CrtYd" user "Package Geometry/Place Bound Bottom")
		(35 "F.Fab" user "Ref Des/Assembly Top")
		(33 "B.Fab" user "Ref Des/Assembly Bottom")
	)
	(footprint ""
		(layer "B.Cu")
		(at 231.882696 -324.980554 180)
		(property "Reference" "R1246"
			(at 0 0 0)
			(layer "B.SilkS")
			(hide yes)
			(effects
				(font
					(size 1.27 1.27)
				)
				(justify mirror)
			)
		)
		(property "Value" ""
			(at 0 0 0)
			(layer "B.Fab")
			(effects
				(font
					(size 1.27 1.27)
				)
				(justify mirror)
			)
		)
		(duplicate_pad_numbers_are_jumpers no)
		(fp_line
			(start 0.7874 0.4064)
			(end 0.7874 -0.4064)
			(stroke
				(width 0.1524)
				(type default)
			)
			(layer "B.SilkS")
		)
		(fp_line
			(start 0.7874 -0.4064)
			(end -0.7874 -0.4064)
			(stroke
				(width 0.1524)
				(type default)
			)
			(layer "B.SilkS")
		)
		(fp_line
			(start -0.7874 0.4064)
			(end 0.7874 0.4064)
			(stroke
				(width 0.1524)
				(type default)
			)
			(layer "B.SilkS")
		)
		(fp_line
			(start -0.7874 -0.4064)
			(end -0.7874 0.4064)
			(stroke
				(width 0.1524)
				(type default)
			)
			(layer "B.SilkS")
		)
		(fp_line
			(start 0.67945 0.3048)
			(end 0.67945 -0.305054)
			(stroke
				(width 0.1)
				(type default)
			)
			(layer "B.Fab")
		)
		(fp_line
			(start 0.67945 -0.305054)
			(end 0.12065 -0.305054)
			(stroke
				(width 0.1)
				(type default)
			)
			(layer "B.Fab")
		)
		(fp_line
			(start 0.12065 0.3048)
			(end 0.67945 0.3048)
			(stroke
				(width 0.1)
				(type default)
			)
			(layer "B.Fab")
		)
		(fp_line
			(start 0.12065 0.2794)
			(end 0.12065 0.3048)
			(stroke
				(width 0.1)
				(type default)
			)
			(layer "B.Fab")
		)
		(fp_line
			(start 0.12065 -0.2794)
			(end -0.12065 -0.2794)
			(stroke
				(width 0.1)
				(type default)
			)
			(layer "B.Fab")
		)
		(fp_line
			(start 0.12065 -0.305054)
			(end 0.12065 -0.2794)
			(stroke
				(width 0.1)
				(type default)
			)
			(layer "B.Fab")
		)
		(fp_line
			(start -0.120396 0.3048)
			(end -0.120396 0.2794)
			(stroke
				(width 0.1)
				(type default)
			)
			(layer "B.Fab")
		)
		(fp_line
			(start -0.120396 0.2794)
			(end 0.12065 0.2794)
			(stroke
				(width 0.1)
				(type default)
			)
			(layer "B.Fab")
		)
		(fp_line
			(start -0.12065 -0.2794)
			(end -0.12065 -0.3048)
			(stroke
				(width 0.1)
				(type default)
			)
			(layer "B.Fab")
		)
		(fp_line
			(start -0.12065 -0.3048)
			(end -0.67945 -0.3048)
			(stroke
				(width 0.1)
				(type default)
			)
			(layer "B.Fab")
		)
		(fp_line
			(start -0.67945 0.3048)
			(end -0.120396 0.3048)
			(stroke
				(width 0.1)
				(type default)
			)
			(layer "B.Fab")
		)
		(fp_line
			(start -0.67945 -0.3048)
			(end -0.67945 0.3048)
			(stroke
				(width 0.1)
				(type default)
			)
			(layer "B.Fab")
		)
		(pad "1" smd rect
			(at 0.40005 0 180)
			(size 0.4572 0.508)
			(layers "B.Cu" "B.Mask" "B.Paste")
			(net "P1V8_CPU0_RT_1D_ADC")
		)
		(pad "2" smd rect
			(at -0.40005 0 180)
			(size 0.4572 0.508)
			(layers "B.Cu" "B.Mask" "B.Paste")
			(net "P1V8_CPU0_RT_1D_ADC_MAM")
		)
	)
	(footprint ""
		(layer "B.Cu")
		(at 327.823068 -338.927694 -90)
		(property "Reference" "PC93_2"
			(at 0 0 90)
			(layer "B.SilkS")
			(hide yes)
			(effects
				(font
					(size 1.27 1.27)
				)
				(justify mirror)
			)
		)
		(property "Value" ""
			(at 0 0 90)
			(layer "B.Fab")
			(effects
				(font
					(size 1.27 1.27)
				)
				(justify mirror)
			)
		)
		(duplicate_pad_numbers_are_jumpers no)
		(fp_line
			(start -1.524 0.762)
			(end 1.524 0.762)
			(stroke
				(width 0.1524)
				(type default)
			)
			(layer "B.SilkS")
		)
		(fp_line
			(start 1.524 0.762)
			(end 1.524 -0.762)
			(stroke
				(width 0.1524)
				(type default)
			)
			(layer "B.SilkS")
		)
		(fp_line
			(start -1.524 -0.762)
			(end -1.524 0.762)
			(stroke
				(width 0.1524)
				(type default)
			)
			(layer "B.SilkS")
		)
		(fp_line
			(start 1.524 -0.762)
			(end -1.524 -0.762)
			(stroke
				(width 0.1524)
				(type default)
			)
			(layer "B.SilkS")
		)
		(fp_line
			(start -1.1049 0.724916)
			(end -1.1049 -0.724916)
			(stroke
				(width 0.1)
				(type default)
			)
			(layer "B.Fab")
		)
		(fp_line
			(start 1.1049 0.724916)
			(end -1.1049 0.724916)
			(stroke
				(width 0.1)
				(type default)
			)
			(layer "B.Fab")
		)
		(fp_line
			(start -1.1049 -0.724916)
			(end 1.1049 -0.724916)
			(stroke
				(width 0.1)
				(type default)
			)
			(layer "B.Fab")
		)
		(fp_line
			(start 1.1049 -0.724916)
			(end 1.1049 0.724916)
			(stroke
				(width 0.1)
				(type default)
			)
			(layer "B.Fab")
		)
		(pad "1" smd rect
			(at 0.889 0 270)
			(size 1.016 1.27)
			(layers "B.Cu" "B.Mask" "B.Paste")
			(net "SW_P12V_AUX_PVDDCR_CPU1_P0_FLT")
		)
		(pad "2" smd rect
			(at -0.889 0 270)
			(size 1.016 1.27)
			(layers "B.Cu" "B.Mask" "B.Paste")
			(net "GND")
		)
	)
	(footprint ""
		(layer "B.Cu")
		(at 299.82414 -192.660016)
		(property "Reference" "C143"
			(at 0 0 0)
			(layer "B.SilkS")
			(hide yes)
			(effects
				(font
					(size 1.27 1.27)
				)
				(justify mirror)
			)
		)
		(property "Value" ""
			(at 0 0 0)
			(layer "B.Fab")
			(effects
				(font
					(size 1.27 1.27)
				)
				(justify mirror)
			)
		)
		(duplicate_pad_numbers_are_jumpers no)
		(fp_line
			(start -1.524 -0.762)
			(end -1.524 0.762)
			(stroke
				(width 0.1524)
				(type default)
			)
			(layer "B.SilkS")
		)
		(fp_line
			(start -1.524 0.762)
			(end 1.524 0.762)
			(stroke
				(width 0.1524)
				(type default)
			)
			(layer "B.SilkS")
		)
		(fp_line
			(start 1.524 -0.762)
			(end -1.524 -0.762)
			(stroke
				(width 0.1524)
				(type default)
			)
			(layer "B.SilkS")
		)
		(fp_line
			(start 1.524 0.762)
			(end 1.524 -0.762)
			(stroke
				(width 0.1524)
				(type default)
			)
			(layer "B.SilkS")
		)
		(fp_line
			(start -1.1049 -0.724916)
			(end 1.1049 -0.724916)
			(stroke
				(width 0.1)
				(type default)
			)
			(layer "B.Fab")
		)
		(fp_line
			(start -1.1049 0.724916)
			(end -1.1049 -0.724916)
			(stroke
				(width 0.1)
				(type default)
			)
			(layer "B.Fab")
		)
		(fp_line
			(start 1.1049 -0.724916)
			(end 1.1049 0.724916)
			(stroke
				(width 0.1)
				(type default)
			)
			(layer "B.Fab")
		)
		(fp_line
			(start 1.1049 0.724916)
			(end -1.1049 0.724916)
			(stroke
				(width 0.1)
				(type default)
			)
			(layer "B.Fab")
		)
		(pad "1" smd rect
			(at 0.889 0)
			(size 1.016 1.27)
			(layers "B.Cu" "B.Mask" "B.Paste")
			(net "P12V_MEM_CPU0")
		)
		(pad "2" smd rect
			(at -0.889 0)
			(size 1.016 1.27)
			(layers "B.Cu" "B.Mask" "B.Paste")
			(net "GND")
		)
	)
	(footprint ""
		(layer "B.Cu")
		(at 138.65352 -36.701222 180)
		(property "Reference" "C6057"
			(at 0 0 0)
			(layer "B.SilkS")
			(hide yes)
			(effects
				(font
					(size 1.27 1.27)
				)
				(justify mirror)
			)
		)
		(property "Value" ""
			(at 0 0 0)
			(layer "B.Fab")
			(effects
				(font
					(size 1.27 1.27)
				)
				(justify mirror)
			)
		)
		(duplicate_pad_numbers_are_jumpers no)
		(fp_line
			(start 0.7874 0.4064)
			(end 0.7874 -0.4064)
			(stroke
				(width 0.1524)
				(type default)
			)
			(layer "B.SilkS")
		)
		(fp_line
			(start 0.7874 -0.4064)
			(end -0.7874 -0.4064)
			(stroke
				(width 0.1524)
				(type default)
			)
			(layer "B.SilkS")
		)
		(fp_line
			(start -0.7874 0.4064)
			(end 0.7874 0.4064)
			(stroke
				(width 0.1524)
				(type default)
			)
			(layer "B.SilkS")
		)
		(fp_line
			(start -0.7874 -0.4064)
			(end -0.7874 0.4064)
			(stroke
				(width 0.1524)
				(type default)
			)
			(layer "B.SilkS")
		)
		(fp_line
			(start 0.67945 0.3048)
			(end 0.67945 -0.305054)
			(stroke
				(width 0.1)
				(type default)
			)
			(layer "B.Fab")
		)
		(fp_line
			(start 0.67945 -0.305054)
			(end 0.12065 -0.305054)
			(stroke
				(width 0.1)
				(type default)
			)
			(layer "B.Fab")
		)
		(fp_line
			(start 0.12065 0.3048)
			(end 0.67945 0.3048)
			(stroke
				(width 0.1)
				(type default)
			)
			(layer "B.Fab")
		)
		(fp_line
			(start 0.12065 0.2794)
			(end 0.12065 0.3048)
			(stroke
				(width 0.1)
				(type default)
			)
			(layer "B.Fab")
		)
		(fp_line
			(start 0.12065 -0.2794)
			(end -0.12065 -0.2794)
			(stroke
				(width 0.1)
				(type default)
			)
			(layer "B.Fab")
		)
		(fp_line
			(start 0.12065 -0.305054)
			(end 0.12065 -0.2794)
			(stroke
				(width 0.1)
				(type default)
			)
			(layer "B.Fab")
		)
		(fp_line
			(start -0.120396 0.3048)
			(end -0.120396 0.2794)
			(stroke
				(width 0.1)
				(type default)
			)
			(layer "B.Fab")
		)
		(fp_line
			(start -0.120396 0.2794)
			(end 0.12065 0.2794)
			(stroke
				(width 0.1)
				(type default)
			)
			(layer "B.Fab")
		)
		(fp_line
			(start -0.12065 -0.2794)
			(end -0.12065 -0.3048)
			(stroke
				(width 0.1)
				(type default)
			)
			(layer "B.Fab")
		)
		(fp_line
			(start -0.12065 -0.3048)
			(end -0.67945 -0.3048)
			(stroke
				(width 0.1)
				(type default)
			)
			(layer "B.Fab")
		)
		(fp_line
			(start -0.67945 0.3048)
			(end -0.120396 0.3048)
			(stroke
				(width 0.1)
				(type default)
			)
			(layer "B.Fab")
		)
		(fp_line
			(start -0.67945 -0.3048)
			(end -0.67945 0.3048)
			(stroke
				(width 0.1)
				(type default)
			)
			(layer "B.Fab")
		)
		(pad "1" smd circle
			(at 0.40005 0)
			(size 0 0)
			(layers "B.Cu" "B.Mask" "B.Paste")
			(net "P1V2_AUX")
		)
		(pad "2" smd circle
			(at -0.40005 0)
			(size 0 0)
			(layers "B.Cu" "B.Mask" "B.Paste")
			(net "GND")
		)
	)
	(footprint ""
		(layer "B.Cu")
		(at 353.900232 -257.455162 180)
		(property "Reference" "C2644"
			(at 0 0 0)
			(layer "B.SilkS")
			(hide yes)
			(effects
				(font
					(size 1.27 1.27)
				)
				(justify mirror)
			)
		)
		(property "Value" ""
			(at 0 0 0)
			(layer "B.Fab")
			(effects
				(font
					(size 1.27 1.27)
				)
				(justify mirror)
			)
		)
		(duplicate_pad_numbers_are_jumpers no)
		(fp_line
			(start 0.7874 0.4064)
			(end 0.7874 -0.4064)
			(stroke
				(width 0.1524)
				(type default)
			)
			(layer "B.SilkS")
		)
		(fp_line
			(start 0.7874 -0.4064)
			(end -0.7874 -0.4064)
			(stroke
				(width 0.1524)
				(type default)
			)
			(layer "B.SilkS")
		)
		(fp_line
			(start -0.7874 0.4064)
			(end 0.7874 0.4064)
			(stroke
				(width 0.1524)
				(type default)
			)
			(layer "B.SilkS")
		)
		(fp_line
			(start -0.7874 -0.4064)
			(end -0.7874 0.4064)
			(stroke
				(width 0.1524)
				(type default)
			)
			(layer "B.SilkS")
		)
		(fp_line
			(start 0.67945 0.3048)
			(end 0.67945 -0.305054)
			(stroke
				(width 0.1)
				(type default)
			)
			(layer "B.Fab")
		)
		(fp_line
			(start 0.67945 -0.305054)
			(end 0.12065 -0.305054)
			(stroke
				(width 0.1)
				(type default)
			)
			(layer "B.Fab")
		)
		(fp_line
			(start 0.12065 0.3048)
			(end 0.67945 0.3048)
			(stroke
				(width 0.1)
				(type default)
			)
			(layer "B.Fab")
		)
		(fp_line
			(start 0.12065 0.2794)
			(end 0.12065 0.3048)
			(stroke
				(width 0.1)
				(type default)
			)
			(layer "B.Fab")
		)
		(fp_line
			(start 0.12065 -0.2794)
			(end -0.12065 -0.2794)
			(stroke
				(width 0.1)
				(type default)
			)
			(layer "B.Fab")
		)
		(fp_line
			(start 0.12065 -0.305054)
			(end 0.12065 -0.2794)
			(stroke
				(width 0.1)
				(type default)
			)
			(layer "B.Fab")
		)
		(fp_line
			(start -0.120396 0.3048)
			(end -0.120396 0.2794)
			(stroke
				(width 0.1)
				(type default)
			)
			(layer "B.Fab")
		)
		(fp_line
			(start -0.120396 0.2794)
			(end 0.12065 0.2794)
			(stroke
				(width 0.1)
				(type default)
			)
			(layer "B.Fab")
		)
		(fp_line
			(start -0.12065 -0.2794)
			(end -0.12065 -0.3048)
			(stroke
				(width 0.1)
				(type default)
			)
			(layer "B.Fab")
		)
		(fp_line
			(start -0.12065 -0.3048)
			(end -0.67945 -0.3048)
			(stroke
				(width 0.1)
				(type default)
			)
			(layer "B.Fab")
		)
		(fp_line
			(start -0.67945 0.3048)
			(end -0.120396 0.3048)
			(stroke
				(width 0.1)
				(type default)
			)
			(layer "B.Fab")
		)
		(fp_line
			(start -0.67945 -0.3048)
			(end -0.67945 0.3048)
			(stroke
				(width 0.1)
				(type default)
			)
			(layer "B.Fab")
		)
		(pad "1" smd circle
			(at 0.40005 0)
			(size 0 0)
			(layers "B.Cu" "B.Mask" "B.Paste")
			(net "PVDDIO_P0")
		)
		(pad "2" smd circle
			(at -0.40005 0)
			(size 0 0)
			(layers "B.Cu" "B.Mask" "B.Paste")
			(net "GND")
		)
	)
	(footprint ""
		(layer "B.Cu")
		(at 359.417112 -261.747762 90)
		(property "Reference" "C2610"
			(at 0 0 90)
			(layer "B.SilkS")
			(hide yes)
			(effects
				(font
					(size 1.27 1.27)
				)
				(justify mirror)
			)
		)
		(property "Value" ""
			(at 0 0 90)
			(layer "B.Fab")
			(effects
				(font
					(size 1.27 1.27)
				)
				(justify mirror)
			)
		)
		(duplicate_pad_numbers_are_jumpers no)
		(fp_line
			(start 0.7874 -0.4064)
			(end -0.7874 -0.4064)
			(stroke
				(width 0.1524)
				(type default)
			)
			(layer "B.SilkS")
		)
		(fp_line
			(start -0.7874 -0.4064)
			(end -0.7874 0.4064)
			(stroke
				(width 0.1524)
				(type default)
			)
			(layer "B.SilkS")
		)
		(fp_line
			(start 0.7874 0.4064)
			(end 0.7874 -0.4064)
			(stroke
				(width 0.1524)
				(type default)
			)
			(layer "B.SilkS")
		)
		(fp_line
			(start -0.7874 0.4064)
			(end 0.7874 0.4064)
			(stroke
				(width 0.1524)
				(type default)
			)
			(layer "B.SilkS")
		)
		(fp_line
			(start 0.67945 -0.305054)
			(end 0.12065 -0.305054)
			(stroke
				(width 0.1)
				(type default)
			)
			(layer "B.Fab")
		)
		(fp_line
			(start 0.12065 -0.305054)
			(end 0.12065 -0.2794)
			(stroke
				(width 0.1)
				(type default)
			)
			(layer "B.Fab")
		)
		(fp_line
			(start -0.12065 -0.3048)
			(end -0.67945 -0.3048)
			(stroke
				(width 0.1)
				(type default)
			)
			(layer "B.Fab")
		)
		(fp_line
			(start -0.67945 -0.3048)
			(end -0.67945 0.3048)
			(stroke
				(width 0.1)
				(type default)
			)
			(layer "B.Fab")
		)
		(fp_line
			(start 0.12065 -0.2794)
			(end -0.12065 -0.2794)
			(stroke
				(width 0.1)
				(type default)
			)
			(layer "B.Fab")
		)
		(fp_line
			(start -0.12065 -0.2794)
			(end -0.12065 -0.3048)
			(stroke
				(width 0.1)
				(type default)
			)
			(layer "B.Fab")
		)
		(fp_line
			(start 0.12065 0.2794)
			(end 0.12065 0.3048)
			(stroke
				(width 0.1)
				(type default)
			)
			(layer "B.Fab")
		)
		(fp_line
			(start -0.120396 0.2794)
			(end 0.12065 0.2794)
			(stroke
				(width 0.1)
				(type default)
			)
			(layer "B.Fab")
		)
		(fp_line
			(start 0.67945 0.3048)
			(end 0.67945 -0.305054)
			(stroke
				(width 0.1)
				(type default)
			)
			(layer "B.Fab")
		)
		(fp_line
			(start 0.12065 0.3048)
			(end 0.67945 0.3048)
			(stroke
				(width 0.1)
				(type default)
			)
			(layer "B.Fab")
		)
		(fp_line
			(start -0.120396 0.3048)
			(end -0.120396 0.2794)
			(stroke
				(width 0.1)
				(type default)
			)
			(layer "B.Fab")
		)
		(fp_line
			(start -0.67945 0.3048)
			(end -0.120396 0.3048)
			(stroke
				(width 0.1)
				(type default)
			)
			(layer "B.Fab")
		)
		(pad "1" smd circle
			(at 0.40005 0 270)
			(size 0 0)
			(layers "B.Cu" "B.Mask" "B.Paste")
			(net "PVDD11_S3_P0")
		)
		(pad "2" smd circle
			(at -0.40005 0 270)
			(size 0 0)
			(layers "B.Cu" "B.Mask" "B.Paste")
			(net "GND")
		)
	)
	(footprint ""
		(layer "B.Cu")
		(at 163.387532 -432.37658 90)
		(property "Reference" "R4130"
			(at 0 0 90)
			(layer "B.SilkS")
			(hide yes)
			(effects
				(font
					(size 1.27 1.27)
				)
				(justify mirror)
			)
		)
		(property "Value" ""
			(at 0 0 90)
			(layer "B.Fab")
			(effects
				(font
					(size 1.27 1.27)
				)
				(justify mirror)
			)
		)
		(duplicate_pad_numbers_are_jumpers no)
		(fp_line
			(start 0.7874 -0.4064)
			(end -0.7874 -0.4064)
			(stroke
				(width 0.1524)
				(type default)
			)
			(layer "B.SilkS")
		)
		(fp_line
			(start -0.7874 -0.4064)
			(end -0.7874 0.4064)
			(stroke
				(width 0.1524)
				(type default)
			)
			(layer "B.SilkS")
		)
		(fp_line
			(start 0.7874 0.4064)
			(end 0.7874 -0.4064)
			(stroke
				(width 0.1524)
				(type default)
			)
			(layer "B.SilkS")
		)
		(fp_line
			(start -0.7874 0.4064)
			(end 0.7874 0.4064)
			(stroke
				(width 0.1524)
				(type default)
			)
			(layer "B.SilkS")
		)
		(fp_line
			(start 0.67945 -0.305054)
			(end 0.12065 -0.305054)
			(stroke
				(width 0.1)
				(type default)
			)
			(layer "B.Fab")
		)
		(fp_line
			(start 0.12065 -0.305054)
			(end 0.12065 -0.2794)
			(stroke
				(width 0.1)
				(type default)
			)
			(layer "B.Fab")
		)
		(fp_line
			(start -0.12065 -0.3048)
			(end -0.67945 -0.3048)
			(stroke
				(width 0.1)
				(type default)
			)
			(layer "B.Fab")
		)
		(fp_line
			(start -0.67945 -0.3048)
			(end -0.67945 0.3048)
			(stroke
				(width 0.1)
				(type default)
			)
			(layer "B.Fab")
		)
		(fp_line
			(start 0.12065 -0.2794)
			(end -0.12065 -0.2794)
			(stroke
				(width 0.1)
				(type default)
			)
			(layer "B.Fab")
		)
		(fp_line
			(start -0.12065 -0.2794)
			(end -0.12065 -0.3048)
			(stroke
				(width 0.1)
				(type default)
			)
			(layer "B.Fab")
		)
		(fp_line
			(start 0.12065 0.2794)
			(end 0.12065 0.3048)
			(stroke
				(width 0.1)
				(type default)
			)
			(layer "B.Fab")
		)
		(fp_line
			(start -0.120396 0.2794)
			(end 0.12065 0.2794)
			(stroke
				(width 0.1)
				(type default)
			)
			(layer "B.Fab")
		)
		(fp_line
			(start 0.67945 0.3048)
			(end 0.67945 -0.305054)
			(stroke
				(width 0.1)
				(type default)
			)
			(layer "B.Fab")
		)
		(fp_line
			(start 0.12065 0.3048)
			(end 0.67945 0.3048)
			(stroke
				(width 0.1)
				(type default)
			)
			(layer "B.Fab")
		)
		(fp_line
			(start -0.120396 0.3048)
			(end -0.120396 0.2794)
			(stroke
				(width 0.1)
				(type default)
			)
			(layer "B.Fab")
		)
		(fp_line
			(start -0.67945 0.3048)
			(end -0.120396 0.3048)
			(stroke
				(width 0.1)
				(type default)
			)
			(layer "B.Fab")
		)
		(pad "1" smd circle
			(at 0.40005 0 270)
			(size 0 0)
			(layers "B.Cu" "B.Mask" "B.Paste")
			(net "P3V3_AUX")
		)
		(pad "2" smd circle
			(at -0.40005 0 270)
			(size 0 0)
			(layers "B.Cu" "B.Mask" "B.Paste")
			(net "GPU_3V3IO_RSVD1_FFU_ISO")
		)
	)
)
